(kicad_pcb
	(version 20260206)
	(generator "pcbnew")
	(generator_version "10.0")
	(general
		(thickness 1.6)
		(legacy_teardrops no)
	)
	(paper "A4")
	(title_block
		(title "9052_F0T_PDB_Converter_Brick_F_V03_1208_1600_OCP.brd")
		(comment 1 "Grand Teton / footprints 493-498 of 578")
	)
	(layers
		(0 "F.Cu" signal "TOP")
		(4 "In1.Cu" signal "GND")
		(6 "In2.Cu" signal "IN1")
		(8 "In3.Cu" signal "GND1")
		(10 "In4.Cu" signal "VCC")
		(12 "In5.Cu" signal "VCC1")
		(14 "In6.Cu" signal "GND2")
		(16 "In7.Cu" signal "IN2")
		(18 "In8.Cu" signal "GND3")
		(2 "B.Cu" signal "BOTTOM")
		(9 "F.Adhes" user "F.Adhesive")
		(11 "B.Adhes" user "B.Adhesive")
		(13 "F.Paste" user "Package Geometry/Pastemask Top")
		(15 "B.Paste" user "Package Geometry/Pastemask Bottom")
		(5 "F.SilkS" user "Ref Des/Silkscreen Top")
		(7 "B.SilkS" user "Ref Des/Silkscreen Bottom")
		(1 "F.Mask" user "Board Geometry/Soldermask Top")
		(3 "B.Mask" user "Board Geometry/Soldermask Bottom")
		(17 "Dwgs.User" user "User.Drawings")
		(19 "Cmts.User" user "User.Comments")
		(21 "Eco1.User" user "User.Eco1")
		(23 "Eco2.User" user "User.Eco2")
		(25 "Edge.Cuts" user "Board Geometry/Outline")
		(27 "Margin" user)
		(31 "F.CrtYd" user "Package Geometry/Place Bound Top")
		(29 "B.CrtYd" user "Package Geometry/Place Bound Bottom")
		(35 "F.Fab" user "Ref Des/Assembly Top")
		(33 "B.Fab" user "Ref Des/Assembly Bottom")
	)
	(footprint ""
		(layer "B.Cu")
		(at 273.685 -29.337 90)
		(property "Reference" "R5917"
			(at 0 0 90)
			(layer "B.SilkS")
			(hide yes)
			(effects
				(font
					(size 1.27 1.27)
				)
				(justify mirror)
			)
		)
		(property "Value" ""
			(at 0 0 90)
			(layer "B.Fab")
			(effects
				(font
					(size 1.27 1.27)
				)
				(justify mirror)
			)
		)
		(duplicate_pad_numbers_are_jumpers no)
		(fp_line
			(start 0.7874 -0.4064)
			(end -0.7874 -0.4064)
			(stroke
				(width 0.1524)
				(type default)
			)
			(layer "B.SilkS")
		)
		(fp_line
			(start -0.7874 -0.4064)
			(end -0.7874 0.4064)
			(stroke
				(width 0.1524)
				(type default)
			)
			(layer "B.SilkS")
		)
		(fp_line
			(start 0.7874 0.4064)
			(end 0.7874 -0.4064)
			(stroke
				(width 0.1524)
				(type default)
			)
			(layer "B.SilkS")
		)
		(fp_line
			(start -0.7874 0.4064)
			(end 0.7874 0.4064)
			(stroke
				(width 0.1524)
				(type default)
			)
			(layer "B.SilkS")
		)
		(fp_line
			(start 0.67945 -0.305054)
			(end 0.12065 -0.305054)
			(stroke
				(width 0.1)
				(type default)
			)
			(layer "B.Fab")
		)
		(fp_line
			(start 0.12065 -0.305054)
			(end 0.12065 -0.2794)
			(stroke
				(width 0.1)
				(type default)
			)
			(layer "B.Fab")
		)
		(fp_line
			(start -0.12065 -0.3048)
			(end -0.67945 -0.3048)
			(stroke
				(width 0.1)
				(type default)
			)
			(layer "B.Fab")
		)
		(fp_line
			(start -0.67945 -0.3048)
			(end -0.67945 0.3048)
			(stroke
				(width 0.1)
				(type default)
			)
			(layer "B.Fab")
		)
		(fp_line
			(start 0.12065 -0.2794)
			(end -0.12065 -0.2794)
			(stroke
				(width 0.1)
				(type default)
			)
			(layer "B.Fab")
		)
		(fp_line
			(start -0.12065 -0.2794)
			(end -0.12065 -0.3048)
			(stroke
				(width 0.1)
				(type default)
			)
			(layer "B.Fab")
		)
		(fp_line
			(start 0.12065 0.2794)
			(end 0.12065 0.3048)
			(stroke
				(width 0.1)
				(type default)
			)
			(layer "B.Fab")
		)
		(fp_line
			(start -0.120396 0.2794)
			(end 0.12065 0.2794)
			(stroke
				(width 0.1)
				(type default)
			)
			(layer "B.Fab")
		)
		(fp_line
			(start 0.67945 0.3048)
			(end 0.67945 -0.305054)
			(stroke
				(width 0.1)
				(type default)
			)
			(layer "B.Fab")
		)
		(fp_line
			(start 0.12065 0.3048)
			(end 0.67945 0.3048)
			(stroke
				(width 0.1)
				(type default)
			)
			(layer "B.Fab")
		)
		(fp_line
			(start -0.120396 0.3048)
			(end -0.120396 0.2794)
			(stroke
				(width 0.1)
				(type default)
			)
			(layer "B.Fab")
		)
		(fp_line
			(start -0.67945 0.3048)
			(end -0.120396 0.3048)
			(stroke
				(width 0.1)
				(type default)
			)
			(layer "B.Fab")
		)
		(pad "1" smd circle
			(at 0.40005 0 270)
			(size 0 0)
			(layers "B.Cu" "B.Mask" "B.Paste")
			(net "FM_AC_PWR_CYCLE_BUF")
		)
		(pad "2" smd circle
			(at -0.40005 0 270)
			(size 0 0)
			(layers "B.Cu" "B.Mask" "B.Paste")
			(net "FM_AC_PWR_CYCLE_R_BUF")
		)
	)
	(footprint ""
		(layer "B.Cu")
		(at 216.662 -91.059 90)
		(property "Reference" "C8"
			(at 0 0 90)
			(layer "B.SilkS")
			(hide yes)
			(effects
				(font
					(size 1.27 1.27)
				)
				(justify mirror)
			)
		)
		(property "Value" ""
			(at 0 0 90)
			(layer "B.Fab")
			(effects
				(font
					(size 1.27 1.27)
				)
				(justify mirror)
			)
		)
		(duplicate_pad_numbers_are_jumpers no)
		(fp_line
			(start 0.7874 -0.4064)
			(end -0.7874 -0.4064)
			(stroke
				(width 0.1524)
				(type default)
			)
			(layer "B.SilkS")
		)
		(fp_line
			(start -0.7874 -0.4064)
			(end -0.7874 0.4064)
			(stroke
				(width 0.1524)
				(type default)
			)
			(layer "B.SilkS")
		)
		(fp_line
			(start 0.7874 0.4064)
			(end 0.7874 -0.4064)
			(stroke
				(width 0.1524)
				(type default)
			)
			(layer "B.SilkS")
		)
		(fp_line
			(start -0.7874 0.4064)
			(end 0.7874 0.4064)
			(stroke
				(width 0.1524)
				(type default)
			)
			(layer "B.SilkS")
		)
		(fp_line
			(start 0.67945 -0.305054)
			(end 0.12065 -0.305054)
			(stroke
				(width 0.1)
				(type default)
			)
			(layer "B.Fab")
		)
		(fp_line
			(start 0.12065 -0.305054)
			(end 0.12065 -0.2794)
			(stroke
				(width 0.1)
				(type default)
			)
			(layer "B.Fab")
		)
		(fp_line
			(start -0.12065 -0.3048)
			(end -0.67945 -0.3048)
			(stroke
				(width 0.1)
				(type default)
			)
			(layer "B.Fab")
		)
		(fp_line
			(start -0.67945 -0.3048)
			(end -0.67945 0.3048)
			(stroke
				(width 0.1)
				(type default)
			)
			(layer "B.Fab")
		)
		(fp_line
			(start 0.12065 -0.2794)
			(end -0.12065 -0.2794)
			(stroke
				(width 0.1)
				(type default)
			)
			(layer "B.Fab")
		)
		(fp_line
			(start -0.12065 -0.2794)
			(end -0.12065 -0.3048)
			(stroke
				(width 0.1)
				(type default)
			)
			(layer "B.Fab")
		)
		(fp_line
			(start 0.12065 0.2794)
			(end 0.12065 0.3048)
			(stroke
				(width 0.1)
				(type default)
			)
			(layer "B.Fab")
		)
		(fp_line
			(start -0.120396 0.2794)
			(end 0.12065 0.2794)
			(stroke
				(width 0.1)
				(type default)
			)
			(layer "B.Fab")
		)
		(fp_line
			(start 0.67945 0.3048)
			(end 0.67945 -0.305054)
			(stroke
				(width 0.1)
				(type default)
			)
			(layer "B.Fab")
		)
		(fp_line
			(start 0.12065 0.3048)
			(end 0.67945 0.3048)
			(stroke
				(width 0.1)
				(type default)
			)
			(layer "B.Fab")
		)
		(fp_line
			(start -0.120396 0.3048)
			(end -0.120396 0.2794)
			(stroke
				(width 0.1)
				(type default)
			)
			(layer "B.Fab")
		)
		(fp_line
			(start -0.67945 0.3048)
			(end -0.120396 0.3048)
			(stroke
				(width 0.1)
				(type default)
			)
			(layer "B.Fab")
		)
		(pad "1" smd circle
			(at 0.40005 0 270)
			(size 0 0)
			(layers "B.Cu" "B.Mask" "B.Paste")
			(net "GND")
		)
		(pad "2" smd circle
			(at -0.40005 0 270)
			(size 0 0)
			(layers "B.Cu" "B.Mask" "B.Paste")
			(net "P3V3_AUX")
		)
	)
	(footprint ""
		(layer "B.Cu")
		(at 197.358 -93.853)
		(property "Reference" "R113"
			(at 0 0 0)
			(layer "B.SilkS")
			(hide yes)
			(effects
				(font
					(size 1.27 1.27)
				)
				(justify mirror)
			)
		)
		(property "Value" ""
			(at 0 0 0)
			(layer "B.Fab")
			(effects
				(font
					(size 1.27 1.27)
				)
				(justify mirror)
			)
		)
		(duplicate_pad_numbers_are_jumpers no)
		(fp_line
			(start -0.7874 -0.4064)
			(end -0.7874 0.4064)
			(stroke
				(width 0.1524)
				(type default)
			)
			(layer "B.SilkS")
		)
		(fp_line
			(start -0.7874 0.4064)
			(end 0.7874 0.4064)
			(stroke
				(width 0.1524)
				(type default)
			)
			(layer "B.SilkS")
		)
		(fp_line
			(start 0.7874 -0.4064)
			(end -0.7874 -0.4064)
			(stroke
				(width 0.1524)
				(type default)
			)
			(layer "B.SilkS")
		)
		(fp_line
			(start 0.7874 0.4064)
			(end 0.7874 -0.4064)
			(stroke
				(width 0.1524)
				(type default)
			)
			(layer "B.SilkS")
		)
		(fp_line
			(start -0.67945 -0.3048)
			(end -0.67945 0.3048)
			(stroke
				(width 0.1)
				(type default)
			)
			(layer "B.Fab")
		)
		(fp_line
			(start -0.67945 0.3048)
			(end -0.120396 0.3048)
			(stroke
				(width 0.1)
				(type default)
			)
			(layer "B.Fab")
		)
		(fp_line
			(start -0.12065 -0.3048)
			(end -0.67945 -0.3048)
			(stroke
				(width 0.1)
				(type default)
			)
			(layer "B.Fab")
		)
		(fp_line
			(start -0.12065 -0.2794)
			(end -0.12065 -0.3048)
			(stroke
				(width 0.1)
				(type default)
			)
			(layer "B.Fab")
		)
		(fp_line
			(start -0.120396 0.2794)
			(end 0.12065 0.2794)
			(stroke
				(width 0.1)
				(type default)
			)
			(layer "B.Fab")
		)
		(fp_line
			(start -0.120396 0.3048)
			(end -0.120396 0.2794)
			(stroke
				(width 0.1)
				(type default)
			)
			(layer "B.Fab")
		)
		(fp_line
			(start 0.12065 -0.305054)
			(end 0.12065 -0.2794)
			(stroke
				(width 0.1)
				(type default)
			)
			(layer "B.Fab")
		)
		(fp_line
			(start 0.12065 -0.2794)
			(end -0.12065 -0.2794)
			(stroke
				(width 0.1)
				(type default)
			)
			(layer "B.Fab")
		)
		(fp_line
			(start 0.12065 0.2794)
			(end 0.12065 0.3048)
			(stroke
				(width 0.1)
				(type default)
			)
			(layer "B.Fab")
		)
		(fp_line
			(start 0.12065 0.3048)
			(end 0.67945 0.3048)
			(stroke
				(width 0.1)
				(type default)
			)
			(layer "B.Fab")
		)
		(fp_line
			(start 0.67945 -0.305054)
			(end 0.12065 -0.305054)
			(stroke
				(width 0.1)
				(type default)
			)
			(layer "B.Fab")
		)
		(fp_line
			(start 0.67945 0.3048)
			(end 0.67945 -0.305054)
			(stroke
				(width 0.1)
				(type default)
			)
			(layer "B.Fab")
		)
		(pad "1" smd circle
			(at 0.40005 0 180)
			(size 0 0)
			(layers "B.Cu" "B.Mask" "B.Paste")
			(net "RST_SMB_PDB_BUF_N")
		)
		(pad "2" smd circle
			(at -0.40005 0 180)
			(size 0 0)
			(layers "B.Cu" "B.Mask" "B.Paste")
			(net "RST_SMB_PDB_BUF_R1_N")
		)
	)
	(footprint ""
		(layer "B.Cu")
		(at 56.642 -78.613)
		(property "Reference" "R182"
			(at 0 0 0)
			(layer "B.SilkS")
			(hide yes)
			(effects
				(font
					(size 1.27 1.27)
				)
				(justify mirror)
			)
		)
		(property "Value" ""
			(at 0 0 0)
			(layer "B.Fab")
			(effects
				(font
					(size 1.27 1.27)
				)
				(justify mirror)
			)
		)
		(duplicate_pad_numbers_are_jumpers no)
		(fp_line
			(start -0.7874 -0.4064)
			(end -0.7874 0.4064)
			(stroke
				(width 0.1524)
				(type default)
			)
			(layer "B.SilkS")
		)
		(fp_line
			(start -0.7874 0.4064)
			(end 0.7874 0.4064)
			(stroke
				(width 0.1524)
				(type default)
			)
			(layer "B.SilkS")
		)
		(fp_line
			(start 0.7874 -0.4064)
			(end -0.7874 -0.4064)
			(stroke
				(width 0.1524)
				(type default)
			)
			(layer "B.SilkS")
		)
		(fp_line
			(start 0.7874 0.4064)
			(end 0.7874 -0.4064)
			(stroke
				(width 0.1524)
				(type default)
			)
			(layer "B.SilkS")
		)
		(fp_line
			(start -0.67945 -0.3048)
			(end -0.67945 0.3048)
			(stroke
				(width 0.1)
				(type default)
			)
			(layer "B.Fab")
		)
		(fp_line
			(start -0.67945 0.3048)
			(end -0.120396 0.3048)
			(stroke
				(width 0.1)
				(type default)
			)
			(layer "B.Fab")
		)
		(fp_line
			(start -0.12065 -0.3048)
			(end -0.67945 -0.3048)
			(stroke
				(width 0.1)
				(type default)
			)
			(layer "B.Fab")
		)
		(fp_line
			(start -0.12065 -0.2794)
			(end -0.12065 -0.3048)
			(stroke
				(width 0.1)
				(type default)
			)
			(layer "B.Fab")
		)
		(fp_line
			(start -0.120396 0.2794)
			(end 0.12065 0.2794)
			(stroke
				(width 0.1)
				(type default)
			)
			(layer "B.Fab")
		)
		(fp_line
			(start -0.120396 0.3048)
			(end -0.120396 0.2794)
			(stroke
				(width 0.1)
				(type default)
			)
			(layer "B.Fab")
		)
		(fp_line
			(start 0.12065 -0.305054)
			(end 0.12065 -0.2794)
			(stroke
				(width 0.1)
				(type default)
			)
			(layer "B.Fab")
		)
		(fp_line
			(start 0.12065 -0.2794)
			(end -0.12065 -0.2794)
			(stroke
				(width 0.1)
				(type default)
			)
			(layer "B.Fab")
		)
		(fp_line
			(start 0.12065 0.2794)
			(end 0.12065 0.3048)
			(stroke
				(width 0.1)
				(type default)
			)
			(layer "B.Fab")
		)
		(fp_line
			(start 0.12065 0.3048)
			(end 0.67945 0.3048)
			(stroke
				(width 0.1)
				(type default)
			)
			(layer "B.Fab")
		)
		(fp_line
			(start 0.67945 -0.305054)
			(end 0.12065 -0.305054)
			(stroke
				(width 0.1)
				(type default)
			)
			(layer "B.Fab")
		)
		(fp_line
			(start 0.67945 0.3048)
			(end 0.67945 -0.305054)
			(stroke
				(width 0.1)
				(type default)
			)
			(layer "B.Fab")
		)
		(pad "1" smd circle
			(at 0.40005 0 180)
			(size 0 0)
			(layers "B.Cu" "B.Mask" "B.Paste")
			(net "P3V3_AUX")
		)
		(pad "2" smd circle
			(at -0.40005 0 180)
			(size 0 0)
			(layers "B.Cu" "B.Mask" "B.Paste")
			(net "P12V_BRICK3_ALERT_N")
		)
	)
	(footprint ""
		(layer "B.Cu")
		(at 174.493174 -76.327 180)
		(property "Reference" "R196"
			(at 0 0 0)
			(layer "B.SilkS")
			(hide yes)
			(effects
				(font
					(size 1.27 1.27)
				)
				(justify mirror)
			)
		)
		(property "Value" ""
			(at 0 0 0)
			(layer "B.Fab")
			(effects
				(font
					(size 1.27 1.27)
				)
				(justify mirror)
			)
		)
		(duplicate_pad_numbers_are_jumpers no)
		(fp_line
			(start 0.7874 0.4064)
			(end 0.7874 -0.4064)
			(stroke
				(width 0.1524)
				(type default)
			)
			(layer "B.SilkS")
		)
		(fp_line
			(start 0.7874 -0.4064)
			(end -0.7874 -0.4064)
			(stroke
				(width 0.1524)
				(type default)
			)
			(layer "B.SilkS")
		)
		(fp_line
			(start -0.7874 0.4064)
			(end 0.7874 0.4064)
			(stroke
				(width 0.1524)
				(type default)
			)
			(layer "B.SilkS")
		)
		(fp_line
			(start -0.7874 -0.4064)
			(end -0.7874 0.4064)
			(stroke
				(width 0.1524)
				(type default)
			)
			(layer "B.SilkS")
		)
		(fp_line
			(start 0.67945 0.3048)
			(end 0.67945 -0.305054)
			(stroke
				(width 0.1)
				(type default)
			)
			(layer "B.Fab")
		)
		(fp_line
			(start 0.67945 -0.305054)
			(end 0.12065 -0.305054)
			(stroke
				(width 0.1)
				(type default)
			)
			(layer "B.Fab")
		)
		(fp_line
			(start 0.12065 0.3048)
			(end 0.67945 0.3048)
			(stroke
				(width 0.1)
				(type default)
			)
			(layer "B.Fab")
		)
		(fp_line
			(start 0.12065 0.2794)
			(end 0.12065 0.3048)
			(stroke
				(width 0.1)
				(type default)
			)
			(layer "B.Fab")
		)
		(fp_line
			(start 0.12065 -0.2794)
			(end -0.12065 -0.2794)
			(stroke
				(width 0.1)
				(type default)
			)
			(layer "B.Fab")
		)
		(fp_line
			(start 0.12065 -0.305054)
			(end 0.12065 -0.2794)
			(stroke
				(width 0.1)
				(type default)
			)
			(layer "B.Fab")
		)
		(fp_line
			(start -0.120396 0.3048)
			(end -0.120396 0.2794)
			(stroke
				(width 0.1)
				(type default)
			)
			(layer "B.Fab")
		)
		(fp_line
			(start -0.120396 0.2794)
			(end 0.12065 0.2794)
			(stroke
				(width 0.1)
				(type default)
			)
			(layer "B.Fab")
		)
		(fp_line
			(start -0.12065 -0.2794)
			(end -0.12065 -0.3048)
			(stroke
				(width 0.1)
				(type default)
			)
			(layer "B.Fab")
		)
		(fp_line
			(start -0.12065 -0.3048)
			(end -0.67945 -0.3048)
			(stroke
				(width 0.1)
				(type default)
			)
			(layer "B.Fab")
		)
		(fp_line
			(start -0.67945 0.3048)
			(end -0.120396 0.3048)
			(stroke
				(width 0.1)
				(type default)
			)
			(layer "B.Fab")
		)
		(fp_line
			(start -0.67945 -0.3048)
			(end -0.67945 0.3048)
			(stroke
				(width 0.1)
				(type default)
			)
			(layer "B.Fab")
		)
		(pad "1" smd circle
			(at 0.40005 0)
			(size 0 0)
			(layers "B.Cu" "B.Mask" "B.Paste")
			(net "SMB_P52V_VPDB_SDA")
		)
		(pad "2" smd circle
			(at -0.40005 0)
			(size 0 0)
			(layers "B.Cu" "B.Mask" "B.Paste")
			(net "SMB_BRICK2_SDA")
		)
	)
	(footprint ""
		(layer "B.Cu")
		(at 37.397436 -59.960002 -90)
		(property "Reference" "C92"
			(at 0 0 90)
			(layer "B.SilkS")
			(hide yes)
			(effects
				(font
					(size 1.27 1.27)
				)
				(justify mirror)
			)
		)
		(property "Value" ""
			(at 0 0 90)
			(layer "B.Fab")
			(effects
				(font
					(size 1.27 1.27)
				)
				(justify mirror)
			)
		)
		(duplicate_pad_numbers_are_jumpers no)
		(fp_line
			(start -1.524 0.762)
			(end 1.524 0.762)
			(stroke
				(width 0.1524)
				(type default)
			)
			(layer "B.SilkS")
		)
		(fp_line
			(start 1.524 0.762)
			(end 1.524 -0.762)
			(stroke
				(width 0.1524)
				(type default)
			)
			(layer "B.SilkS")
		)
		(fp_line
			(start -1.524 -0.762)
			(end -1.524 0.762)
			(stroke
				(width 0.1524)
				(type default)
			)
			(layer "B.SilkS")
		)
		(fp_line
			(start 1.524 -0.762)
			(end -1.524 -0.762)
			(stroke
				(width 0.1524)
				(type default)
			)
			(layer "B.SilkS")
		)
		(fp_line
			(start -1.1049 0.724916)
			(end -1.1049 -0.724916)
			(stroke
				(width 0.1)
				(type default)
			)
			(layer "B.Fab")
		)
		(fp_line
			(start 1.1049 0.724916)
			(end -1.1049 0.724916)
			(stroke
				(width 0.1)
				(type default)
			)
			(layer "B.Fab")
		)
		(fp_line
			(start -1.1049 -0.724916)
			(end 1.1049 -0.724916)
			(stroke
				(width 0.1)
				(type default)
			)
			(layer "B.Fab")
		)
		(fp_line
			(start 1.1049 -0.724916)
			(end 1.1049 0.724916)
			(stroke
				(width 0.1)
				(type default)
			)
			(layer "B.Fab")
		)
		(pad "1" smd rect
			(at 0.889 0 270)
			(size 1.016 1.27)
			(layers "B.Cu" "B.Mask" "B.Paste")
			(net "P12V_HPDB")
		)
		(pad "2" smd rect
			(at -0.889 0 270)
			(size 1.016 1.27)
			(layers "B.Cu" "B.Mask" "B.Paste")
			(net "GND")
		)
	)
)
